(kicad_pcb
	(version 20260206)
	(generator "pcbnew")
	(generator_version "10.0")
	(general
		(thickness 1.6)
		(legacy_teardrops no)
	)
	(paper "A4")
	(title_block
		(title "peb — Lightning_PEB_BRD.brd")
		(comment 1 "Lightning (Wiwynn / Facebook NVMe JBOF) / footprint 1445 of 2563 (U1), pads 699-814 of 1311")
	)
	(layers
		(0 "F.Cu" signal "TOP")
		(4 "In1.Cu" signal "L2GND")
		(6 "In2.Cu" signal "L3")
		(8 "In3.Cu" signal "L4VCC")
		(10 "In4.Cu" signal "L5VCC")
		(12 "In5.Cu" signal "L6")
		(14 "In6.Cu" signal "L7GND")
		(2 "B.Cu" signal "BOTTOM")
		(9 "F.Adhes" user "F.Adhesive")
		(11 "B.Adhes" user "B.Adhesive")
		(13 "F.Paste" user "Package Geometry/Pastemask Top")
		(15 "B.Paste" user "Package Geometry/Pastemask Bottom")
		(5 "F.SilkS" user "Ref Des/Silkscreen Top")
		(7 "B.SilkS" user "Ref Des/Silkscreen Bottom")
		(1 "F.Mask" user "Board Geometry/Soldermask Top")
		(3 "B.Mask" user "Board Geometry/Soldermask Bottom")
		(17 "Dwgs.User" user "User.Drawings")
		(19 "Cmts.User" user "User.Comments")
		(21 "Eco1.User" user "User.Eco1")
		(23 "Eco2.User" user "User.Eco2")
		(25 "Edge.Cuts" user "Board Geometry/Outline")
		(27 "Margin" user)
		(31 "F.CrtYd" user "Package Geometry/Place Bound Top")
		(29 "B.CrtYd" user "Package Geometry/Place Bound Bottom")
		(35 "F.Fab" user "Ref Des/Assembly Top")
		(33 "B.Fab" user "Ref Des/Assembly Bottom")
	)
	(footprint ""
		(layer "F.Cu")
		(at 240.599976 -47.999904 -90)
		(property "Reference" "U1"
			(at 0 0 270)
			(layer "F.SilkS")
			(hide yes)
			(effects
				(font
					(size 1.27 1.27)
				)
			)
		)
		(property "Value" "PM8546A-FEIP-GP"
			(at -25.785064 -6.40334 270)
			(unlocked yes)
			(layer "F.Fab")
			(hide yes)
			(effects
				(font
					(size 1.016 1.016)
					(thickness 0.1524)
				)
			)
		)
		(property "Device Type" "BGA1311C37D5H134"
			(at -25.785064 -7.92734 270)
			(unlocked yes)
			(layer "F.Fab")
			(hide yes)
			(effects
				(font
					(size 1.016 1.016)
					(thickness 0.1524)
				)
			)
		)
		(duplicate_pad_numbers_are_jumpers no)
		(pad "D3" smd circle
			(at -15.999968 -14.99997 270)
			(size 0.4572 0.4572)
			(layers "F.Cu" "F.Mask" "F.Paste")
			(net "GND")
		)
		(pad "D4" smd circle
			(at -14.99997 -14.99997 270)
			(size 0.4572 0.4572)
			(layers "F.Cu" "F.Mask" "F.Paste")
			(net "PCIE_RX_N34")
		)
		(pad "D5" smd circle
			(at -13.999972 -14.99997 270)
			(size 0.4572 0.4572)
			(layers "F.Cu" "F.Mask" "F.Paste")
			(net "PCIE_RX_P34")
		)
		(pad "D6" smd circle
			(at -12.999974 -14.99997 270)
			(size 0.4572 0.4572)
			(layers "F.Cu" "F.Mask" "F.Paste")
			(net "GND")
		)
		(pad "D7" smd circle
			(at -11.999976 -14.99997 270)
			(size 0.4572 0.4572)
			(layers "F.Cu" "F.Mask" "F.Paste")
			(net "GND")
		)
		(pad "D8" smd circle
			(at -10.999978 -14.99997 270)
			(size 0.4572 0.4572)
			(layers "F.Cu" "F.Mask" "F.Paste")
			(net "GND")
		)
		(pad "D9" smd circle
			(at -9.99998 -14.99997 270)
			(size 0.4572 0.4572)
			(layers "F.Cu" "F.Mask" "F.Paste")
			(net "PCIE_RX_N30")
		)
		(pad "D10" smd circle
			(at -8.999982 -14.99997 270)
			(size 0.4572 0.4572)
			(layers "F.Cu" "F.Mask" "F.Paste")
			(net "GND")
		)
		(pad "D11" smd circle
			(at -7.999984 -14.99997 270)
			(size 0.4572 0.4572)
			(layers "F.Cu" "F.Mask" "F.Paste")
			(net "PCIE_RX_N28")
		)
		(pad "D12" smd circle
			(at -6.999986 -14.99997 270)
			(size 0.4572 0.4572)
			(layers "F.Cu" "F.Mask" "F.Paste")
			(net "GND")
		)
		(pad "D13" smd circle
			(at -5.999988 -14.99997 270)
			(size 0.4572 0.4572)
			(layers "F.Cu" "F.Mask" "F.Paste")
			(net "PCIE_RX_N26")
		)
		(pad "D14" smd circle
			(at -4.99999 -14.99997 270)
			(size 0.4572 0.4572)
			(layers "F.Cu" "F.Mask" "F.Paste")
			(net "GND")
		)
		(pad "D15" smd circle
			(at -3.999992 -14.99997 270)
			(size 0.4572 0.4572)
			(layers "F.Cu" "F.Mask" "F.Paste")
			(net "PCIE_RX_N24")
		)
		(pad "D16" smd circle
			(at -2.999994 -14.99997 270)
			(size 0.4572 0.4572)
			(layers "F.Cu" "F.Mask" "F.Paste")
			(net "GND")
		)
		(pad "D17" smd circle
			(at -1.999996 -14.99997 270)
			(size 0.4572 0.4572)
			(layers "F.Cu" "F.Mask" "F.Paste")
			(net "GND")
		)
		(pad "D18" smd circle
			(at -0.999998 -14.99997 270)
			(size 0.4572 0.4572)
			(layers "F.Cu" "F.Mask" "F.Paste")
			(net "PCIE_RX_N22")
		)
		(pad "D19" smd circle
			(at 0 -14.99997 270)
			(size 0.4572 0.4572)
			(layers "F.Cu" "F.Mask" "F.Paste")
			(net "GND")
		)
		(pad "D20" smd circle
			(at 0.999998 -14.99997 270)
			(size 0.4572 0.4572)
			(layers "F.Cu" "F.Mask" "F.Paste")
			(net "PCIE_RX_N20")
		)
		(pad "D21" smd circle
			(at 1.999996 -14.99997 270)
			(size 0.4572 0.4572)
			(layers "F.Cu" "F.Mask" "F.Paste")
			(net "GND")
		)
		(pad "D22" smd circle
			(at 2.999994 -14.99997 270)
			(size 0.4572 0.4572)
			(layers "F.Cu" "F.Mask" "F.Paste")
			(net "PCIE_RX_N18")
		)
		(pad "D23" smd circle
			(at 3.999992 -14.99997 270)
			(size 0.4572 0.4572)
			(layers "F.Cu" "F.Mask" "F.Paste")
			(net "GND")
		)
		(pad "D24" smd circle
			(at 4.99999 -14.99997 270)
			(size 0.4572 0.4572)
			(layers "F.Cu" "F.Mask" "F.Paste")
			(net "PCIE_RX_N16")
		)
		(pad "D25" smd circle
			(at 5.999988 -14.99997 270)
			(size 0.4572 0.4572)
			(layers "F.Cu" "F.Mask" "F.Paste")
			(net "GND")
		)
		(pad "D26" smd circle
			(at 6.999986 -14.99997 270)
			(size 0.4572 0.4572)
			(layers "F.Cu" "F.Mask" "F.Paste")
			(net "GND")
		)
		(pad "D27" smd circle
			(at 7.999984 -14.99997 270)
			(size 0.4572 0.4572)
			(layers "F.Cu" "F.Mask" "F.Paste")
			(net "PCIE_RX_N14")
		)
		(pad "D28" smd circle
			(at 8.999982 -14.99997 270)
			(size 0.4572 0.4572)
			(layers "F.Cu" "F.Mask" "F.Paste")
			(net "GND")
		)
		(pad "D29" smd circle
			(at 9.99998 -14.99997 270)
			(size 0.4572 0.4572)
			(layers "F.Cu" "F.Mask" "F.Paste")
			(net "PCIE_RX_N12")
		)
		(pad "D30" smd circle
			(at 10.999978 -14.99997 270)
			(size 0.4572 0.4572)
			(layers "F.Cu" "F.Mask" "F.Paste")
			(net "GND")
		)
		(pad "D31" smd circle
			(at 11.999976 -14.99997 270)
			(size 0.4572 0.4572)
			(layers "F.Cu" "F.Mask" "F.Paste")
			(net "PCIE_RX_N10")
		)
		(pad "D32" smd circle
			(at 12.999974 -14.99997 270)
			(size 0.4572 0.4572)
			(layers "F.Cu" "F.Mask" "F.Paste")
			(net "GND")
		)
		(pad "D33" smd circle
			(at 13.999972 -14.99997 270)
			(size 0.4572 0.4572)
			(layers "F.Cu" "F.Mask" "F.Paste")
			(net "PCIE_RX_N8")
		)
		(pad "D34" smd circle
			(at 14.99997 -14.99997 270)
			(size 0.4572 0.4572)
			(layers "F.Cu" "F.Mask" "F.Paste")
			(net "GND")
		)
		(pad "D35" smd circle
			(at 15.999968 -14.99997 270)
			(size 0.4572 0.4572)
			(layers "F.Cu" "F.Mask" "F.Paste")
			(net "GND")
		)
		(pad "D36" smd circle
			(at 16.999966 -14.99997 270)
			(size 0.4572 0.4572)
			(layers "F.Cu" "F.Mask" "F.Paste")
			(net "PCIE_TX_CAP_P4")
		)
		(pad "D37" smd circle
			(at 17.999964 -14.99997 270)
			(size 0.4572 0.4572)
			(layers "F.Cu" "F.Mask" "F.Paste")
			(net "PCIE_TX_CAP_N4")
		)
		(pad "E2" smd circle
			(at -16.999966 -13.999972 270)
			(size 0.4572 0.4572)
			(layers "F.Cu" "F.Mask" "F.Paste")
			(net "PCIE_TX_CAP_N35")
		)
		(pad "E3" smd circle
			(at -15.999968 -13.999972 270)
			(size 0.4572 0.4572)
			(layers "F.Cu" "F.Mask" "F.Paste")
			(net "PCIE_TX_CAP_P35")
		)
		(pad "E4" smd circle
			(at -14.99997 -13.999972 270)
			(size 0.4572 0.4572)
			(layers "F.Cu" "F.Mask" "F.Paste")
			(net "GND")
		)
		(pad "E5" smd circle
			(at -13.999972 -13.999972 270)
			(size 0.4572 0.4572)
			(layers "F.Cu" "F.Mask" "F.Paste")
			(net "PCIE_RX_N35")
		)
		(pad "E6" smd circle
			(at -12.999974 -13.999972 270)
			(size 0.4572 0.4572)
			(layers "F.Cu" "F.Mask" "F.Paste")
			(net "PCIE_RX_P35")
		)
		(pad "E7" smd circle
			(at -11.999976 -13.999972 270)
			(size 0.4572 0.4572)
			(layers "F.Cu" "F.Mask" "F.Paste")
			(net "GND")
		)
		(pad "E8" smd circle
			(at -10.999978 -13.999972 270)
			(size 0.4572 0.4572)
			(layers "F.Cu" "F.Mask" "F.Paste")
			(net "PCIE_RX_N31")
		)
		(pad "E9" smd circle
			(at -9.99998 -13.999972 270)
			(size 0.4572 0.4572)
			(layers "F.Cu" "F.Mask" "F.Paste")
			(net "PCIE_RX_P30")
		)
		(pad "E10" smd circle
			(at -8.999982 -13.999972 270)
			(size 0.4572 0.4572)
			(layers "F.Cu" "F.Mask" "F.Paste")
			(net "PCIE_RX_N29")
		)
		(pad "E11" smd circle
			(at -7.999984 -13.999972 270)
			(size 0.4572 0.4572)
			(layers "F.Cu" "F.Mask" "F.Paste")
			(net "PCIE_RX_P28")
		)
		(pad "E12" smd circle
			(at -6.999986 -13.999972 270)
			(size 0.4572 0.4572)
			(layers "F.Cu" "F.Mask" "F.Paste")
			(net "PCIE_RX_N27")
		)
		(pad "E13" smd circle
			(at -5.999988 -13.999972 270)
			(size 0.4572 0.4572)
			(layers "F.Cu" "F.Mask" "F.Paste")
			(net "PCIE_RX_P26")
		)
		(pad "E14" smd circle
			(at -4.99999 -13.999972 270)
			(size 0.4572 0.4572)
			(layers "F.Cu" "F.Mask" "F.Paste")
			(net "PCIE_RX_N25")
		)
		(pad "E15" smd circle
			(at -3.999992 -13.999972 270)
			(size 0.4572 0.4572)
			(layers "F.Cu" "F.Mask" "F.Paste")
			(net "PCIE_RX_P24")
		)
		(pad "E16" smd circle
			(at -2.999994 -13.999972 270)
			(size 0.4572 0.4572)
			(layers "F.Cu" "F.Mask" "F.Paste")
			(net "GND")
		)
		(pad "E17" smd circle
			(at -1.999996 -13.999972 270)
			(size 0.4572 0.4572)
			(layers "F.Cu" "F.Mask" "F.Paste")
			(net "PCIE_RX_N23")
		)
		(pad "E18" smd circle
			(at -0.999998 -13.999972 270)
			(size 0.4572 0.4572)
			(layers "F.Cu" "F.Mask" "F.Paste")
			(net "PCIE_RX_P22")
		)
		(pad "E19" smd circle
			(at 0 -13.999972 270)
			(size 0.4572 0.4572)
			(layers "F.Cu" "F.Mask" "F.Paste")
			(net "PCIE_RX_N21")
		)
		(pad "E20" smd circle
			(at 0.999998 -13.999972 270)
			(size 0.4572 0.4572)
			(layers "F.Cu" "F.Mask" "F.Paste")
			(net "PCIE_RX_P20")
		)
		(pad "E21" smd circle
			(at 1.999996 -13.999972 270)
			(size 0.4572 0.4572)
			(layers "F.Cu" "F.Mask" "F.Paste")
			(net "PCIE_RX_N19")
		)
		(pad "E22" smd circle
			(at 2.999994 -13.999972 270)
			(size 0.4572 0.4572)
			(layers "F.Cu" "F.Mask" "F.Paste")
			(net "PCIE_RX_P18")
		)
		(pad "E23" smd circle
			(at 3.999992 -13.999972 270)
			(size 0.4572 0.4572)
			(layers "F.Cu" "F.Mask" "F.Paste")
			(net "PCIE_RX_N17")
		)
		(pad "E24" smd circle
			(at 4.99999 -13.999972 270)
			(size 0.4572 0.4572)
			(layers "F.Cu" "F.Mask" "F.Paste")
			(net "PCIE_RX_P16")
		)
		(pad "E25" smd circle
			(at 5.999988 -13.999972 270)
			(size 0.4572 0.4572)
			(layers "F.Cu" "F.Mask" "F.Paste")
			(net "GND")
		)
		(pad "E26" smd circle
			(at 6.999986 -13.999972 270)
			(size 0.4572 0.4572)
			(layers "F.Cu" "F.Mask" "F.Paste")
			(net "PCIE_RX_N15")
		)
		(pad "E27" smd circle
			(at 7.999984 -13.999972 270)
			(size 0.4572 0.4572)
			(layers "F.Cu" "F.Mask" "F.Paste")
			(net "PCIE_RX_P14")
		)
		(pad "E28" smd circle
			(at 8.999982 -13.999972 270)
			(size 0.4572 0.4572)
			(layers "F.Cu" "F.Mask" "F.Paste")
			(net "PCIE_RX_N13")
		)
		(pad "E29" smd circle
			(at 9.99998 -13.999972 270)
			(size 0.4572 0.4572)
			(layers "F.Cu" "F.Mask" "F.Paste")
			(net "PCIE_RX_P12")
		)
		(pad "E30" smd circle
			(at 10.999978 -13.999972 270)
			(size 0.4572 0.4572)
			(layers "F.Cu" "F.Mask" "F.Paste")
			(net "PCIE_RX_N11")
		)
		(pad "E31" smd circle
			(at 11.999976 -13.999972 270)
			(size 0.4572 0.4572)
			(layers "F.Cu" "F.Mask" "F.Paste")
			(net "PCIE_RX_P10")
		)
		(pad "E32" smd circle
			(at 12.999974 -13.999972 270)
			(size 0.4572 0.4572)
			(layers "F.Cu" "F.Mask" "F.Paste")
			(net "PCIE_RX_N9")
		)
		(pad "E33" smd circle
			(at 13.999972 -13.999972 270)
			(size 0.4572 0.4572)
			(layers "F.Cu" "F.Mask" "F.Paste")
			(net "PCIE_RX_P8")
		)
		(pad "E34" smd circle
			(at 14.99997 -13.999972 270)
			(size 0.4572 0.4572)
			(layers "F.Cu" "F.Mask" "F.Paste")
			(net "GND")
		)
		(pad "E35" smd circle
			(at 15.999968 -13.999972 270)
			(size 0.4572 0.4572)
			(layers "F.Cu" "F.Mask" "F.Paste")
			(net "PCIE_TX_CAP_P3")
		)
		(pad "E36" smd circle
			(at 16.999966 -13.999972 270)
			(size 0.4572 0.4572)
			(layers "F.Cu" "F.Mask" "F.Paste")
			(net "PCIE_TX_CAP_N3")
		)
		(pad "F1" smd circle
			(at -17.999964 -12.999974 270)
			(size 0.4572 0.4572)
			(layers "F.Cu" "F.Mask" "F.Paste")
			(net "PCIE_TX_CAP_N36")
		)
		(pad "F2" smd circle
			(at -16.999966 -12.999974 270)
			(size 0.4572 0.4572)
			(layers "F.Cu" "F.Mask" "F.Paste")
			(net "PCIE_TX_CAP_P36")
		)
		(pad "F3" smd circle
			(at -15.999968 -12.999974 270)
			(size 0.4572 0.4572)
			(layers "F.Cu" "F.Mask" "F.Paste")
			(net "GND")
		)
		(pad "F4" smd circle
			(at -14.99997 -12.999974 270)
			(size 0.4572 0.4572)
			(layers "F.Cu" "F.Mask" "F.Paste")
			(net "PCIE_RX_N36")
		)
		(pad "F5" smd circle
			(at -13.999972 -12.999974 270)
			(size 0.4572 0.4572)
			(layers "F.Cu" "F.Mask" "F.Paste")
			(net "PCIE_RX_P36")
		)
		(pad "F6" smd circle
			(at -12.999974 -12.999974 270)
			(size 0.4572 0.4572)
			(layers "F.Cu" "F.Mask" "F.Paste")
			(net "GND")
		)
		(pad "F7" smd circle
			(at -11.999976 -12.999974 270)
			(size 0.4572 0.4572)
			(layers "F.Cu" "F.Mask" "F.Paste")
			(net "DUT_AVD_PCIE")
		)
		(pad "F8" smd circle
			(at -10.999978 -12.999974 270)
			(size 0.4572 0.4572)
			(layers "F.Cu" "F.Mask" "F.Paste")
			(net "PCIE_RX_P31")
		)
		(pad "F9" smd circle
			(at -9.99998 -12.999974 270)
			(size 0.4572 0.4572)
			(layers "F.Cu" "F.Mask" "F.Paste")
			(net "GND")
		)
		(pad "F10" smd circle
			(at -8.999982 -12.999974 270)
			(size 0.4572 0.4572)
			(layers "F.Cu" "F.Mask" "F.Paste")
			(net "PCIE_RX_P29")
		)
		(pad "F11" smd circle
			(at -7.999984 -12.999974 270)
			(size 0.4572 0.4572)
			(layers "F.Cu" "F.Mask" "F.Paste")
			(net "GND")
		)
		(pad "F12" smd circle
			(at -6.999986 -12.999974 270)
			(size 0.4572 0.4572)
			(layers "F.Cu" "F.Mask" "F.Paste")
			(net "PCIE_RX_P27")
		)
		(pad "F13" smd circle
			(at -5.999988 -12.999974 270)
			(size 0.4572 0.4572)
			(layers "F.Cu" "F.Mask" "F.Paste")
			(net "GND")
		)
		(pad "F14" smd circle
			(at -4.99999 -12.999974 270)
			(size 0.4572 0.4572)
			(layers "F.Cu" "F.Mask" "F.Paste")
			(net "PCIE_RX_P25")
		)
		(pad "F15" smd circle
			(at -3.999992 -12.999974 270)
			(size 0.4572 0.4572)
			(layers "F.Cu" "F.Mask" "F.Paste")
			(net "GND")
		)
		(pad "F16" smd circle
			(at -2.999994 -12.999974 270)
			(size 0.4572 0.4572)
			(layers "F.Cu" "F.Mask" "F.Paste")
			(net "DUT_AVD_PCIE")
		)
		(pad "F17" smd circle
			(at -1.999996 -12.999974 270)
			(size 0.4572 0.4572)
			(layers "F.Cu" "F.Mask" "F.Paste")
			(net "PCIE_RX_P23")
		)
		(pad "F18" smd circle
			(at -0.999998 -12.999974 270)
			(size 0.4572 0.4572)
			(layers "F.Cu" "F.Mask" "F.Paste")
			(net "GND")
		)
		(pad "F19" smd circle
			(at 0 -12.999974 270)
			(size 0.4572 0.4572)
			(layers "F.Cu" "F.Mask" "F.Paste")
			(net "PCIE_RX_P21")
		)
		(pad "F20" smd circle
			(at 0.999998 -12.999974 270)
			(size 0.4572 0.4572)
			(layers "F.Cu" "F.Mask" "F.Paste")
			(net "GND")
		)
		(pad "F21" smd circle
			(at 1.999996 -12.999974 270)
			(size 0.4572 0.4572)
			(layers "F.Cu" "F.Mask" "F.Paste")
			(net "PCIE_RX_P19")
		)
		(pad "F22" smd circle
			(at 2.999994 -12.999974 270)
			(size 0.4572 0.4572)
			(layers "F.Cu" "F.Mask" "F.Paste")
			(net "GND")
		)
		(pad "F23" smd circle
			(at 3.999992 -12.999974 270)
			(size 0.4572 0.4572)
			(layers "F.Cu" "F.Mask" "F.Paste")
			(net "PCIE_RX_P17")
		)
		(pad "F24" smd circle
			(at 4.99999 -12.999974 270)
			(size 0.4572 0.4572)
			(layers "F.Cu" "F.Mask" "F.Paste")
			(net "GND")
		)
		(pad "F25" smd circle
			(at 5.999988 -12.999974 270)
			(size 0.4572 0.4572)
			(layers "F.Cu" "F.Mask" "F.Paste")
			(net "DUT_AVD_PCIE")
		)
		(pad "F26" smd circle
			(at 6.999986 -12.999974 270)
			(size 0.4572 0.4572)
			(layers "F.Cu" "F.Mask" "F.Paste")
			(net "PCIE_RX_P15")
		)
		(pad "F27" smd circle
			(at 7.999984 -12.999974 270)
			(size 0.4572 0.4572)
			(layers "F.Cu" "F.Mask" "F.Paste")
			(net "GND")
		)
		(pad "F28" smd circle
			(at 8.999982 -12.999974 270)
			(size 0.4572 0.4572)
			(layers "F.Cu" "F.Mask" "F.Paste")
			(net "PCIE_RX_P13")
		)
		(pad "F29" smd circle
			(at 9.99998 -12.999974 270)
			(size 0.4572 0.4572)
			(layers "F.Cu" "F.Mask" "F.Paste")
			(net "GND")
		)
		(pad "F30" smd circle
			(at 10.999978 -12.999974 270)
			(size 0.4572 0.4572)
			(layers "F.Cu" "F.Mask" "F.Paste")
			(net "PCIE_RX_P11")
		)
		(pad "F31" smd circle
			(at 11.999976 -12.999974 270)
			(size 0.4572 0.4572)
			(layers "F.Cu" "F.Mask" "F.Paste")
			(net "GND")
		)
		(pad "F32" smd circle
			(at 12.999974 -12.999974 270)
			(size 0.4572 0.4572)
			(layers "F.Cu" "F.Mask" "F.Paste")
			(net "PCIE_RX_P9")
		)
		(pad "F33" smd circle
			(at 13.999972 -12.999974 270)
			(size 0.4572 0.4572)
			(layers "F.Cu" "F.Mask" "F.Paste")
			(net "DUT_AVD_PCIE")
		)
		(pad "F34" smd circle
			(at 14.99997 -12.999974 270)
			(size 0.4572 0.4572)
			(layers "F.Cu" "F.Mask" "F.Paste")
			(net "GND")
		)
		(pad "F35" smd circle
			(at 15.999968 -12.999974 270)
			(size 0.4572 0.4572)
			(layers "F.Cu" "F.Mask" "F.Paste")
			(net "GND")
		)
		(pad "F36" smd circle
			(at 16.999966 -12.999974 270)
			(size 0.4572 0.4572)
			(layers "F.Cu" "F.Mask" "F.Paste")
			(net "PCIE_TX_CAP_P2")
		)
		(pad "F37" smd circle
			(at 17.999964 -12.999974 270)
			(size 0.4572 0.4572)
			(layers "F.Cu" "F.Mask" "F.Paste")
			(net "PCIE_TX_CAP_N2")
		)
		(pad "G2" smd circle
			(at -16.999966 -11.999976 270)
			(size 0.4572 0.4572)
			(layers "F.Cu" "F.Mask" "F.Paste")
			(net "PCIE_TX_CAP_N37")
		)
		(pad "G3" smd circle
			(at -15.999968 -11.999976 270)
			(size 0.4572 0.4572)
			(layers "F.Cu" "F.Mask" "F.Paste")
			(net "PCIE_TX_CAP_P37")
		)
		(pad "G4" smd circle
			(at -14.99997 -11.999976 270)
			(size 0.4572 0.4572)
			(layers "F.Cu" "F.Mask" "F.Paste")
			(net "GND")
		)
		(pad "G5" smd circle
			(at -13.999972 -11.999976 270)
			(size 0.4572 0.4572)
			(layers "F.Cu" "F.Mask" "F.Paste")
			(net "PCIE_RX_N37")
		)
		(pad "G6" smd circle
			(at -12.999974 -11.999976 270)
			(size 0.4572 0.4572)
			(layers "F.Cu" "F.Mask" "F.Paste")
			(net "PCIE_RX_P37")
		)
		(pad "G7" smd circle
			(at -11.999976 -11.999976 270)
			(size 0.4572 0.4572)
			(layers "F.Cu" "F.Mask" "F.Paste")
			(net "DUT_AVD_PCIE")
		)
		(pad "G8" smd circle
			(at -10.999978 -11.999976 270)
			(size 0.4572 0.4572)
			(layers "F.Cu" "F.Mask" "F.Paste")
			(net "DUT_AVD_PCIE")
		)
		(pad "G9" smd circle
			(at -9.99998 -11.999976 270)
			(size 0.4572 0.4572)
			(layers "F.Cu" "F.Mask" "F.Paste")
			(net "DUT_AVD_PCIE")
		)
		(pad "G10" smd circle
			(at -8.999982 -11.999976 270)
			(size 0.4572 0.4572)
			(layers "F.Cu" "F.Mask" "F.Paste")
			(net "DUT_AVD_PCIE")
		)
	)
)
